(kicad_pcb
	(version 20221018)
	(generator pcbnew)
	(general
    (thickness 1.518)
  )
	(paper "A4")
	(title_block
    (title "Kria K26 Devboard")
    (date "2024-03-26")
    (rev "1.2.5")
    (comment 1 "www.antmicro.com")
    (comment 2 "Antmicro Ltd.")
		(comment 9 "footprint 379 of 660 (J_SOM240_1), pads 1-102 of 242")
	)
	(layers
    (0 "F.Cu" mixed)
    (1 "In1.Cu" power)
    (2 "In2.Cu" mixed)
    (3 "In3.Cu" power)
    (4 "In4.Cu" mixed)
    (5 "In5.Cu" power)
    (6 "In6.Cu" mixed)
    (31 "B.Cu" power)
    (32 "B.Adhes" user "B.Adhesive")
    (33 "F.Adhes" user "F.Adhesive")
    (34 "B.Paste" user)
    (35 "F.Paste" user)
    (36 "B.SilkS" user "B.Silkscreen")
    (37 "F.SilkS" user "F.Silkscreen")
    (38 "B.Mask" user)
    (39 "F.Mask" user)
    (40 "Dwgs.User" user "User.Drawings")
    (41 "Cmts.User" user "User.Comments")
    (42 "Eco1.User" user "User.Eco1")
    (43 "Eco2.User" user "User.Eco2")
    (44 "Edge.Cuts" user)
    (45 "Margin" user)
    (46 "B.CrtYd" user "B.Courtyard")
    (47 "F.CrtYd" user "F.Courtyard")
    (48 "B.Fab" user)
    (49 "F.Fab" user)
  )
	(footprint "kria-k26-devboard-footprints:Conn_Plug_Samtec_ADM6_4x60_ADM6-60-01.5-L-4-2-A-TR"
    (layer "F.Cu")
    (at 91.5765 117.6215 -90)
    (property "Author" "Antmicro")
    (property "License" "Apache-2.0")
    (property "MPN" "ADM6-60-01.5-L-4-2-A-TR")
    (property "Manufacturer" "Samtec")
    (property "Sheetfile" "k26_som.kicad_sch")
    (property "Sheetname" "Xilinx K26 SOM")
    (property "ki_description" "Board to Board & Mezzanine Connectors 0.635 mm AcceleRate HD High-Density 4-Row Header 60P")
    (attr smd)
    (fp_text reference "J_SOM240_1" (at -13.8415 -3.7635 -90) (layer "F.SilkS")
        (effects (font (size 0.7 0.7) (thickness 0.15)) (justify left bottom))
    )
    (fp_text value "ADM6-60-01.5-L-4-2-A-TR" (at 0 3.7 -90) (layer "F.Fab") hide
        (effects (font (size 0.7 0.7) (thickness 0.15)) (justify left bottom))
    )
    (pad "" np_thru_hole circle (at -20.136 -1.27 270) (size 0.95 0.95) (drill 0.95) (layers "*.Cu" "*.Mask"))
    (pad "" np_thru_hole circle (at 20.135 0 270) (size 0.95 0.95) (drill 0.95) (layers "*.Cu" "*.Mask"))
    (pad "A01" smd circle (at 18.732 -1.75 270) (size 0.356 0.356) (layers "F.Cu" "F.Paste" "F.Mask")
      (net 438 "/Xilinx K26 SOM/VCC_BATT") (pinfunction "A01") (pintype "passive"))
    (pad "A02" smd circle (at 18.097 -1.75 270) (size 0.356 0.356) (layers "F.Cu" "F.Paste" "F.Mask")
      (net 1 "GND") (pinfunction "A02") (pintype "passive"))
    (pad "A03" smd circle (at 17.462 -1.75 270) (size 0.356 0.356) (layers "F.Cu" "F.Paste" "F.Mask")
      (net 202 "/Camera interface/HPA06_P") (pinfunction "A03") (pintype "passive"))
    (pad "A04" smd circle (at 16.827 -1.75 270) (size 0.356 0.356) (layers "F.Cu" "F.Paste" "F.Mask")
      (net 203 "/Camera interface/HPA06_N") (pinfunction "A04") (pintype "passive"))
    (pad "A05" smd circle (at 16.192 -1.75 270) (size 0.356 0.356) (layers "F.Cu" "F.Paste" "F.Mask")
      (net 1 "GND") (pinfunction "A05") (pintype "passive"))
    (pad "A06" smd circle (at 15.557 -1.75 270) (size 0.356 0.356) (layers "F.Cu" "F.Paste" "F.Mask")
      (net 439 "/Xilinx K26 SOM/HPA06_CLK0_P") (pinfunction "A06") (pintype "passive"))
    (pad "A07" smd circle (at 14.922 -1.75 270) (size 0.356 0.356) (layers "F.Cu" "F.Paste" "F.Mask")
      (net 440 "/Xilinx K26 SOM/HPA06_CLK0_N") (pinfunction "A07") (pintype "passive"))
    (pad "A08" smd circle (at 14.287 -1.75 270) (size 0.356 0.356) (layers "F.Cu" "F.Paste" "F.Mask")
      (net 1 "GND") (pinfunction "A08") (pintype "passive"))
    (pad "A09" smd circle (at 13.652 -1.75 270) (size 0.356 0.356) (layers "F.Cu" "F.Paste" "F.Mask")
      (net 441 "/Xilinx K26 SOM/HPA12_P") (pinfunction "A09") (pintype "passive"))
    (pad "A10" smd circle (at 13.017 -1.75 270) (size 0.356 0.356) (layers "F.Cu" "F.Paste" "F.Mask")
      (net 442 "/Xilinx K26 SOM/HPA12_N") (pinfunction "A10") (pintype "passive"))
    (pad "A11" smd circle (at 12.382 -1.75 270) (size 0.356 0.356) (layers "F.Cu" "F.Paste" "F.Mask")
      (net 1 "GND") (pinfunction "A11") (pintype "passive"))
    (pad "A12" smd circle (at 11.747 -1.75 270) (size 0.356 0.356) (layers "F.Cu" "F.Paste" "F.Mask")
      (net 443 "/Xilinx K26 SOM/HPA13_P") (pinfunction "A12") (pintype "passive"))
    (pad "A13" smd circle (at 11.112 -1.75 270) (size 0.356 0.356) (layers "F.Cu" "F.Paste" "F.Mask")
      (net 444 "/Xilinx K26 SOM/HPA13_N") (pinfunction "A13") (pintype "passive"))
    (pad "A14" smd circle (at 10.477 -1.75 270) (size 0.356 0.356) (layers "F.Cu" "F.Paste" "F.Mask")
      (net 1 "GND") (pinfunction "A14") (pintype "passive"))
    (pad "A15" smd circle (at 9.842 -1.75 270) (size 0.356 0.356) (layers "F.Cu" "F.Paste" "F.Mask")
      (net 197 "/Camera interface/CAM1_VSYNC") (pinfunction "A15") (pintype "passive"))
    (pad "A16" smd circle (at 9.207 -1.75 270) (size 0.356 0.356) (layers "F.Cu" "F.Paste" "F.Mask")
      (net 445 "/Xilinx K26 SOM/HDA10") (pinfunction "A16") (pintype "passive"))
    (pad "A17" smd circle (at 8.572 -1.75 270) (size 0.356 0.356) (layers "F.Cu" "F.Paste" "F.Mask")
      (net 144 "/PMOD/HDA11") (pinfunction "A17") (pintype "passive"))
    (pad "A18" smd circle (at 7.937 -1.75 270) (size 0.356 0.356) (layers "F.Cu" "F.Paste" "F.Mask")
      (net 1 "GND") (pinfunction "A18") (pintype "passive"))
    (pad "A19" smd circle (at 7.302 -1.75 270) (size 0.356 0.356) (layers "F.Cu" "F.Paste" "F.Mask")
      (net 23 "/Power Supply/VCCOEN_PS_M2C") (pinfunction "A19") (pintype "passive"))
    (pad "A20" smd circle (at 6.667 -1.75 270) (size 0.356 0.356) (layers "F.Cu" "F.Paste" "F.Mask")
      (net 24 "/Power Supply/VCCOEN_PL_M2C") (pinfunction "A20") (pintype "passive"))
    (pad "A21" smd circle (at 6.032 -1.75 270) (size 0.356 0.356) (layers "F.Cu" "F.Paste" "F.Mask")
      (net 1 "GND") (pinfunction "A21") (pintype "passive"))
    (pad "A22" smd circle (at 5.397 -1.75 270) (size 0.356 0.356) (layers "F.Cu" "F.Paste" "F.Mask")
      (net 145 "/Debug and JTAG/JTAG_TMS_C2M") (pinfunction "A22") (pintype "passive"))
    (pad "A23" smd circle (at 4.762 -1.75 270) (size 0.356 0.356) (layers "F.Cu" "F.Paste" "F.Mask")
      (net 142 "/Debug and JTAG/JTAG_TDO_M2C") (pinfunction "A23") (pintype "passive"))
    (pad "A24" smd circle (at 4.127 -1.75 270) (size 0.356 0.356) (layers "F.Cu" "F.Paste" "F.Mask")
      (net 141 "/Debug and JTAG/JTAG_TDI_C2M") (pinfunction "A24") (pintype "passive"))
    (pad "A25" smd circle (at 3.492 -1.75 270) (size 0.356 0.356) (layers "F.Cu" "F.Paste" "F.Mask")
      (net 143 "/Debug and JTAG/JTAG_TCK_C2M") (pinfunction "A25") (pintype "passive"))
    (pad "A26" smd circle (at 2.857 -1.75 270) (size 0.356 0.356) (layers "F.Cu" "F.Paste" "F.Mask")
      (net 1 "GND") (pinfunction "A26") (pintype "passive"))
    (pad "A27" smd circle (at 2.222 -1.75 270) (size 0.356 0.356) (layers "F.Cu" "F.Paste" "F.Mask")
      (net 2 "/Xilinx K26 SOM/MODE0_C2M") (pinfunction "A27") (pintype "passive"))
    (pad "A28" smd circle (at 1.587 -1.75 270) (size 0.356 0.356) (layers "F.Cu" "F.Paste" "F.Mask")
      (net 3 "/Xilinx K26 SOM/MODE1_C2M") (pinfunction "A28") (pintype "passive"))
    (pad "A29" smd circle (at 0.952 -1.75 270) (size 0.356 0.356) (layers "F.Cu" "F.Paste" "F.Mask")
      (net 4 "/Xilinx K26 SOM/MODE2_C2M") (pinfunction "A29") (pintype "passive"))
    (pad "A30" smd circle (at 0.317 -1.75 270) (size 0.356 0.356) (layers "F.Cu" "F.Paste" "F.Mask")
      (net 5 "/Xilinx K26 SOM/MODE3_C2M") (pinfunction "A30") (pintype "passive"))
    (pad "A31" smd circle (at -0.318 -1.75 270) (size 0.356 0.356) (layers "F.Cu" "F.Paste" "F.Mask")
      (net 446 "unconnected-(J_SOM240_1-PadA31)") (pinfunction "A31") (pintype "passive+no_connect"))
    (pad "A32" smd circle (at -0.953 -1.75 270) (size 0.356 0.356) (layers "F.Cu" "F.Paste" "F.Mask")
      (net 447 "unconnected-(J_SOM240_1-PadA32)") (pinfunction "A32") (pintype "passive+no_connect"))
    (pad "A33" smd circle (at -1.588 -1.75 270) (size 0.356 0.356) (layers "F.Cu" "F.Paste" "F.Mask")
      (net 1 "GND") (pinfunction "A33") (pintype "passive"))
    (pad "A34" smd circle (at -2.223 -1.75 270) (size 0.356 0.356) (layers "F.Cu" "F.Paste" "F.Mask")
      (net 224 "/Reset logic/MIO41") (pinfunction "A34") (pintype "passive"))
    (pad "A35" smd circle (at -2.858 -1.75 270) (size 0.356 0.356) (layers "F.Cu" "F.Paste" "F.Mask")
      (net 448 "/Xilinx K26 SOM/MIO42") (pinfunction "A35") (pintype "passive"))
    (pad "A36" smd circle (at -3.493 -1.75 270) (size 0.356 0.356) (layers "F.Cu" "F.Paste" "F.Mask")
      (net 127 "/Reset logic/MIO43") (pinfunction "A36") (pintype "passive"))
    (pad "A37" smd circle (at -4.128 -1.75 270) (size 0.356 0.356) (layers "F.Cu" "F.Paste" "F.Mask")
      (net 1 "GND") (pinfunction "A37") (pintype "passive"))
    (pad "A38" smd circle (at -4.763 -1.75 270) (size 0.356 0.356) (layers "F.Cu" "F.Paste" "F.Mask")
      (net 37 "/USB/MIO61") (pinfunction "A38") (pintype "passive"))
    (pad "A39" smd circle (at -5.398 -1.75 270) (size 0.356 0.356) (layers "F.Cu" "F.Paste" "F.Mask")
      (net 38 "/USB/MIO62") (pinfunction "A39") (pintype "passive"))
    (pad "A40" smd circle (at -6.033 -1.75 270) (size 0.356 0.356) (layers "F.Cu" "F.Paste" "F.Mask")
      (net 39 "/USB/MIO63") (pinfunction "A40") (pintype "passive"))
    (pad "A41" smd circle (at -6.668 -1.75 270) (size 0.356 0.356) (layers "F.Cu" "F.Paste" "F.Mask")
      (net 1 "GND") (pinfunction "A41") (pintype "passive"))
    (pad "A42" smd circle (at -7.303 -1.75 270) (size 0.356 0.356) (layers "F.Cu" "F.Paste" "F.Mask")
      (net 26 "/Ethernet/MIO73") (pinfunction "A42") (pintype "passive"))
    (pad "A43" smd circle (at -7.938 -1.75 270) (size 0.356 0.356) (layers "F.Cu" "F.Paste" "F.Mask")
      (net 27 "/Ethernet/MIO74") (pinfunction "A43") (pintype "passive"))
    (pad "A44" smd circle (at -8.573 -1.75 270) (size 0.356 0.356) (layers "F.Cu" "F.Paste" "F.Mask")
      (net 28 "/Ethernet/MIO75") (pinfunction "A44") (pintype "passive"))
    (pad "A45" smd circle (at -9.208 -1.75 270) (size 0.356 0.356) (layers "F.Cu" "F.Paste" "F.Mask")
      (net 1 "GND") (pinfunction "A45") (pintype "passive"))
    (pad "A46" smd circle (at -9.843 -1.75 270) (size 0.356 0.356) (layers "F.Cu" "F.Paste" "F.Mask")
      (net 1 "GND") (pinfunction "A46") (pintype "passive"))
    (pad "A47" smd circle (at -10.478 -1.75 270) (size 0.356 0.356) (layers "F.Cu" "F.Paste" "F.Mask")
      (net 92 "/Display Port/GTR_DP1_M2C_P") (pinfunction "A47") (pintype "passive"))
    (pad "A48" smd circle (at -11.113 -1.75 270) (size 0.356 0.356) (layers "F.Cu" "F.Paste" "F.Mask")
      (net 94 "/Display Port/GTR_DP1_M2C_N") (pinfunction "A48") (pintype "passive"))
    (pad "A49" smd circle (at -11.748 -1.75 270) (size 0.356 0.356) (layers "F.Cu" "F.Paste" "F.Mask")
      (net 1 "GND") (pinfunction "A49") (pintype "passive"))
    (pad "A50" smd circle (at -12.383 -1.75 270) (size 0.356 0.356) (layers "F.Cu" "F.Paste" "F.Mask")
      (net 1 "GND") (pinfunction "A50") (pintype "passive"))
    (pad "A51" smd circle (at -13.018 -1.75 270) (size 0.356 0.356) (layers "F.Cu" "F.Paste" "F.Mask")
      (net 107 "/Clock distribution/GTR_REFCLK3_C2M_P") (pinfunction "A51") (pintype "passive"))
    (pad "A52" smd circle (at -13.653 -1.75 270) (size 0.356 0.356) (layers "F.Cu" "F.Paste" "F.Mask")
      (net 108 "/Clock distribution/GTR_REFCLK3_C2M_N") (pinfunction "A52") (pintype "passive"))
    (pad "A53" smd circle (at -14.288 -1.75 270) (size 0.356 0.356) (layers "F.Cu" "F.Paste" "F.Mask")
      (net 1 "GND") (pinfunction "A53") (pintype "passive"))
    (pad "A54" smd circle (at -14.923 -1.75 270) (size 0.356 0.356) (layers "F.Cu" "F.Paste" "F.Mask")
      (net 1 "GND") (pinfunction "A54") (pintype "passive"))
    (pad "A55" smd circle (at -15.558 -1.75 270) (size 0.356 0.356) (layers "F.Cu" "F.Paste" "F.Mask")
      (net 449 "/Xilinx K26 SOM/GTR_DP0_C2M_P") (pinfunction "A55") (pintype "passive"))
    (pad "A56" smd circle (at -16.193 -1.75 270) (size 0.356 0.356) (layers "F.Cu" "F.Paste" "F.Mask")
      (net 450 "/Xilinx K26 SOM/GTR_DP0_C2M_N") (pinfunction "A56") (pintype "passive"))
    (pad "A57" smd circle (at -16.828 -1.75 270) (size 0.356 0.356) (layers "F.Cu" "F.Paste" "F.Mask")
      (net 1 "GND") (pinfunction "A57") (pintype "passive"))
    (pad "A58" smd circle (at -17.463 -1.75 270) (size 0.356 0.356) (layers "F.Cu" "F.Paste" "F.Mask")
      (net 1 "GND") (pinfunction "A58") (pintype "passive"))
    (pad "A59" smd circle (at -18.098 -1.75 270) (size 0.356 0.356) (layers "F.Cu" "F.Paste" "F.Mask")
      (net 8 "SOM_5V0") (pinfunction "A59") (pintype "passive"))
    (pad "A60" smd circle (at -18.733 -1.75 270) (size 0.356 0.356) (layers "F.Cu" "F.Paste" "F.Mask")
      (net 8 "SOM_5V0") (pinfunction "A60") (pintype "passive"))
    (pad "B01" smd circle (at 18.732 -0.791 270) (size 0.356 0.356) (layers "F.Cu" "F.Paste" "F.Mask")
      (net 200 "/Camera interface/HPA05_CC_P") (pinfunction "B01") (pintype "passive"))
    (pad "B02" smd circle (at 18.097 -0.791 270) (size 0.356 0.356) (layers "F.Cu" "F.Paste" "F.Mask")
      (net 201 "/Camera interface/HPA05_CC_N") (pinfunction "B02") (pintype "passive"))
    (pad "B03" smd circle (at 17.462 -0.791 270) (size 0.356 0.356) (layers "F.Cu" "F.Paste" "F.Mask")
      (net 1 "GND") (pinfunction "B03") (pintype "passive"))
    (pad "B04" smd circle (at 16.827 -0.791 270) (size 0.356 0.356) (layers "F.Cu" "F.Paste" "F.Mask")
      (net 218 "/Camera interface/HPA04_P") (pinfunction "B04") (pintype "passive"))
    (pad "B05" smd circle (at 16.192 -0.791 270) (size 0.356 0.356) (layers "F.Cu" "F.Paste" "F.Mask")
      (net 219 "/Camera interface/HPA04_N") (pinfunction "B05") (pintype "passive"))
    (pad "B06" smd circle (at 15.557 -0.791 270) (size 0.356 0.356) (layers "F.Cu" "F.Paste" "F.Mask")
      (net 1 "GND") (pinfunction "B06") (pintype "passive"))
    (pad "B07" smd circle (at 14.922 -0.791 270) (size 0.356 0.356) (layers "F.Cu" "F.Paste" "F.Mask")
      (net 204 "/Camera interface/HPA07_P") (pinfunction "B07") (pintype "passive"))
    (pad "B08" smd circle (at 14.287 -0.791 270) (size 0.356 0.356) (layers "F.Cu" "F.Paste" "F.Mask")
      (net 205 "/Camera interface/HPA07_N") (pinfunction "B08") (pintype "passive"))
    (pad "B09" smd circle (at 13.652 -0.791 270) (size 0.356 0.356) (layers "F.Cu" "F.Paste" "F.Mask")
      (net 1 "GND") (pinfunction "B09") (pintype "passive"))
    (pad "B10" smd circle (at 13.017 -0.791 270) (size 0.356 0.356) (layers "F.Cu" "F.Paste" "F.Mask")
      (net 451 "/Xilinx K26 SOM/HPA11_P") (pinfunction "B10") (pintype "passive"))
    (pad "B11" smd circle (at 12.382 -0.791 270) (size 0.356 0.356) (layers "F.Cu" "F.Paste" "F.Mask")
      (net 452 "/Xilinx K26 SOM/HPA11_N") (pinfunction "B11") (pintype "passive"))
    (pad "B12" smd circle (at 11.747 -0.791 270) (size 0.356 0.356) (layers "F.Cu" "F.Paste" "F.Mask")
      (net 1 "GND") (pinfunction "B12") (pintype "passive"))
    (pad "B13" smd circle (at 11.112 -0.791 270) (size 0.356 0.356) (layers "F.Cu" "F.Paste" "F.Mask")
      (net 20 "PL_3V3") (pinfunction "B13") (pintype "passive"))
    (pad "B14" smd circle (at 10.477 -0.791 270) (size 0.356 0.356) (layers "F.Cu" "F.Paste" "F.Mask")
      (net 20 "PL_3V3") (pinfunction "B14") (pintype "passive"))
    (pad "B15" smd circle (at 9.842 -0.791 270) (size 0.356 0.356) (layers "F.Cu" "F.Paste" "F.Mask")
      (net 1 "GND") (pinfunction "B15") (pintype "passive"))
    (pad "B16" smd circle (at 9.207 -0.791 270) (size 0.356 0.356) (layers "F.Cu" "F.Paste" "F.Mask")
      (net 453 "/Xilinx K26 SOM/HDA03") (pinfunction "B16") (pintype "passive"))
    (pad "B17" smd circle (at 8.572 -0.791 270) (size 0.356 0.356) (layers "F.Cu" "F.Paste" "F.Mask")
      (net 199 "/Camera interface/CAM0_VSYNC") (pinfunction "B17") (pintype "passive"))
    (pad "B18" smd circle (at 7.937 -0.791 270) (size 0.356 0.356) (layers "F.Cu" "F.Paste" "F.Mask")
      (net 454 "/Xilinx K26 SOM/HDA05") (pinfunction "B18") (pintype "passive"))
    (pad "B19" smd circle (at 7.302 -0.791 270) (size 0.356 0.356) (layers "F.Cu" "F.Paste" "F.Mask")
      (net 1 "GND") (pinfunction "B19") (pintype "passive"))
    (pad "B20" smd circle (at 6.667 -0.791 270) (size 0.356 0.356) (layers "F.Cu" "F.Paste" "F.Mask")
      (net 146 "/PMOD/HDA15") (pinfunction "B20") (pintype "passive"))
    (pad "B21" smd circle (at 6.032 -0.791 270) (size 0.356 0.356) (layers "F.Cu" "F.Paste" "F.Mask")
      (net 147 "/PMOD/HDA16_CC") (pinfunction "B21") (pintype "passive"))
    (pad "B22" smd circle (at 5.397 -0.791 270) (size 0.356 0.356) (layers "F.Cu" "F.Paste" "F.Mask")
      (net 148 "/PMOD/HDA17") (pinfunction "B22") (pintype "passive"))
    (pad "B23" smd circle (at 4.762 -0.791 270) (size 0.356 0.356) (layers "F.Cu" "F.Paste" "F.Mask")
      (net 1 "GND") (pinfunction "B23") (pintype "passive"))
    (pad "B24" smd circle (at 4.127 -0.791 270) (size 0.356 0.356) (layers "F.Cu" "F.Paste" "F.Mask")
      (net 455 "/Xilinx K26 SOM/PS_ERROR_OUT_M2C") (pinfunction "B24") (pintype "passive"))
    (pad "B25" smd circle (at 3.492 -0.791 270) (size 0.356 0.356) (layers "F.Cu" "F.Paste" "F.Mask")
      (net 456 "/Xilinx K26 SOM/PS_ERROR_STATUS_M2C") (pinfunction "B25") (pintype "passive"))
    (pad "B26" smd circle (at 2.857 -0.791 270) (size 0.356 0.356) (layers "F.Cu" "F.Paste" "F.Mask")
      (net 457 "/Xilinx K26 SOM/PWROFF_C2M_L") (pinfunction "B26") (pintype "passive"))
    (pad "B27" smd circle (at 2.222 -0.791 270) (size 0.356 0.356) (layers "F.Cu" "F.Paste" "F.Mask")
      (net 1 "GND") (pinfunction "B27") (pintype "passive"))
    (pad "B28" smd circle (at 1.587 -0.791 270) (size 0.356 0.356) (layers "F.Cu" "F.Paste" "F.Mask")
      (net 458 "/Xilinx K26 SOM/MIO35_WD_OUT") (pinfunction "B28") (pintype "passive"))
    (pad "B29" smd circle (at 0.952 -0.791 270) (size 0.356 0.356) (layers "F.Cu" "F.Paste" "F.Mask")
      (net 149 "/Debug and JTAG/MIO36") (pinfunction "B29") (pintype "passive"))
    (pad "B30" smd circle (at 0.317 -0.791 270) (size 0.356 0.356) (layers "F.Cu" "F.Paste" "F.Mask")
      (net 150 "/Debug and JTAG/MIO37") (pinfunction "B30") (pintype "passive"))
    (pad "B31" smd circle (at -0.318 -0.791 270) (size 0.356 0.356) (layers "F.Cu" "F.Paste" "F.Mask")
      (net 1 "GND") (pinfunction "B31") (pintype "passive"))
    (pad "B32" smd circle (at -0.953 -0.791 270) (size 0.356 0.356) (layers "F.Cu" "F.Paste" "F.Mask")
      (net 128 "/Reset logic/MIO38") (pinfunction "B32") (pintype "passive"))
    (pad "B33" smd circle (at -1.588 -0.791 270) (size 0.356 0.356) (layers "F.Cu" "F.Paste" "F.Mask")
      (net 109 "/SD 3.0 card/MIO39") (pinfunction "B33") (pintype "passive"))
    (pad "B34" smd circle (at -2.223 -0.791 270) (size 0.356 0.356) (layers "F.Cu" "F.Paste" "F.Mask")
      (net 459 "/Xilinx K26 SOM/MIO40") (pinfunction "B34") (pintype "passive"))
    (pad "B35" smd circle (at -2.858 -0.791 270) (size 0.356 0.356) (layers "F.Cu" "F.Paste" "F.Mask")
      (net 1 "GND") (pinfunction "B35") (pintype "passive"))
    (pad "B36" smd circle (at -3.493 -0.791 270) (size 0.356 0.356) (layers "F.Cu" "F.Paste" "F.Mask")
      (net 110 "/SD 3.0 card/MIO50") (pinfunction "B36") (pintype "passive"))
    (pad "B37" smd circle (at -4.128 -0.791 270) (size 0.356 0.356) (layers "F.Cu" "F.Paste" "F.Mask")
      (net 123 "/SD 3.0 card/MIO51") (pinfunction "B37") (pintype "passive"))
    (pad "B38" smd circle (at -4.763 -0.791 270) (size 0.356 0.356) (layers "F.Cu" "F.Paste" "F.Mask")
      (net 460 "unconnected-(J_SOM240_1-PadB38)") (pinfunction "B38") (pintype "passive+no_connect"))
    (pad "B39" smd circle (at -5.398 -0.791 270) (size 0.356 0.356) (layers "F.Cu" "F.Paste" "F.Mask")
      (net 1 "GND") (pinfunction "B39") (pintype "passive"))
    (pad "B40" smd circle (at -6.033 -0.791 270) (size 0.356 0.356) (layers "F.Cu" "F.Paste" "F.Mask")
      (net 40 "/USB/MIO58") (pinfunction "B40") (pintype "passive"))
  )
)
